# S9S_MB_2U (Grand Teton) — schematic netlist excerpt (pin names and nets, part order shuffled) for the footprints in the layout excerpt that follows; sources: Cadence DE-HDL packaged netlist, KiCad conversion of 03242023_DA0F0TMBIJ0_F0T_Motherboard_J_brd_V01_OCP.brd

PC2211  Q_CAP  1UF 25V 10% EMPTY  pkg C0402  page 192 : A = GND ; B = P12V_E1S_REG_0
R2590  Q_RES  100 1% CHIP  pkg 0402LF  page 266 : A = SVID_DIO0_CPU0_R ; B = PVNN_TERM_CPU0

(kicad_pcb
	(version 20260206)
	(generator "pcbnew")
	(generator_version "10.0")
	(general
		(thickness 1.6)
		(legacy_teardrops no)
	)
	(paper "A4")
	(title_block
		(title "03242023_DA0F0TMBIJ0_F0T_Motherboard_J_brd_V01_OCP.brd")
		(comment 1 "Grand Teton / footprints 4052-4053 of 6105")
	)
	(layers
		(0 "F.Cu" signal "TOP")
		(4 "In1.Cu" signal "GND")
		(6 "In2.Cu" signal "IN1")
		(8 "In3.Cu" signal "GND1")
		(10 "In4.Cu" signal "IN2")
		(12 "In5.Cu" signal "GND2")
		(14 "In6.Cu" signal "IN3")
		(16 "In7.Cu" signal "GND3")
		(18 "In8.Cu" signal "VCC")
		(20 "In9.Cu" signal "VCC1")
		(22 "In10.Cu" signal "GND4")
		(24 "In11.Cu" signal "IN4")
		(26 "In12.Cu" signal "GND5")
		(28 "In13.Cu" signal "IN5")
		(30 "In14.Cu" signal "GND6")
		(32 "In15.Cu" signal "IN6")
		(34 "In16.Cu" signal "GND7")
		(2 "B.Cu" signal "BOTTOM")
		(9 "F.Adhes" user "F.Adhesive")
		(11 "B.Adhes" user "B.Adhesive")
		(13 "F.Paste" user "Package Geometry/Pastemask Top")
		(15 "B.Paste" user "Package Geometry/Pastemask Bottom")
		(5 "F.SilkS" user "Ref Des/Silkscreen Top")
		(7 "B.SilkS" user "Ref Des/Silkscreen Bottom")
		(1 "F.Mask" user "Board Geometry/Soldermask Top")
		(3 "B.Mask" user "Board Geometry/Soldermask Bottom")
		(17 "Dwgs.User" user "User.Drawings")
		(19 "Cmts.User" user "User.Comments")
		(21 "Eco1.User" user "User.Eco1")
		(23 "Eco2.User" user "User.Eco2")
		(25 "Edge.Cuts" user "Board Geometry/Outline")
		(27 "Margin" user)
		(31 "F.CrtYd" user "Package Geometry/Place Bound Top")
		(29 "B.CrtYd" user "Package Geometry/Place Bound Bottom")
		(35 "F.Fab" user "Ref Des/Assembly Top")
		(33 "B.Fab" user "Ref Des/Assembly Bottom")
	)
	(footprint ""
		(layer "F.Cu")
		(at 251.35967 -44.971462 -90)
		(property "Reference" "PC2211"
			(at 0 0 270)
			(layer "F.SilkS")
			(hide yes)
			(effects
				(font
					(size 1.27 1.27)
				)
			)
		)
		(property "Value" ""
			(at 0 0 270)
			(layer "F.Fab")
			(effects
				(font
					(size 1.27 1.27)
				)
			)
		)
		(duplicate_pad_numbers_are_jumpers no)
		(fp_line
			(start -0.7874 0.4064)
			(end -0.7874 -0.4064)
			(stroke
				(width 0.1524)
				(type default)
			)
			(layer "F.SilkS")
		)
		(fp_line
			(start 0.7874 0.4064)
			(end -0.7874 0.4064)
			(stroke
				(width 0.1524)
				(type default)
			)
			(layer "F.SilkS")
		)
		(fp_line
			(start -0.7874 -0.4064)
			(end 0.7874 -0.4064)
			(stroke
				(width 0.1524)
				(type default)
			)
			(layer "F.SilkS")
		)
		(fp_line
			(start 0.7874 -0.4064)
			(end 0.7874 0.4064)
			(stroke
				(width 0.1524)
				(type default)
			)
			(layer "F.SilkS")
		)
		(fp_line
			(start -0.67945 0.3048)
			(end -0.67945 -0.305054)
			(stroke
				(width 0.1)
				(type default)
			)
			(layer "F.Fab")
		)
		(fp_line
			(start -0.12065 0.3048)
			(end -0.67945 0.3048)
			(stroke
				(width 0.1)
				(type default)
			)
			(layer "F.Fab")
		)
		(fp_line
			(start 0.120396 0.3048)
			(end 0.120396 0.2794)
			(stroke
				(width 0.1)
				(type default)
			)
			(layer "F.Fab")
		)
		(fp_line
			(start 0.67945 0.3048)
			(end 0.120396 0.3048)
			(stroke
				(width 0.1)
				(type default)
			)
			(layer "F.Fab")
		)
		(fp_line
			(start -0.12065 0.2794)
			(end -0.12065 0.3048)
			(stroke
				(width 0.1)
				(type default)
			)
			(layer "F.Fab")
		)
		(fp_line
			(start 0.120396 0.2794)
			(end -0.12065 0.2794)
			(stroke
				(width 0.1)
				(type default)
			)
			(layer "F.Fab")
		)
		(fp_line
			(start -0.12065 -0.2794)
			(end 0.12065 -0.2794)
			(stroke
				(width 0.1)
				(type default)
			)
			(layer "F.Fab")
		)
		(fp_line
			(start 0.12065 -0.2794)
			(end 0.12065 -0.3048)
			(stroke
				(width 0.1)
				(type default)
			)
			(layer "F.Fab")
		)
		(fp_line
			(start 0.12065 -0.3048)
			(end 0.67945 -0.3048)
			(stroke
				(width 0.1)
				(type default)
			)
			(layer "F.Fab")
		)
		(fp_line
			(start 0.67945 -0.3048)
			(end 0.67945 0.3048)
			(stroke
				(width 0.1)
				(type default)
			)
			(layer "F.Fab")
		)
		(fp_line
			(start -0.67945 -0.305054)
			(end -0.12065 -0.305054)
			(stroke
				(width 0.1)
				(type default)
			)
			(layer "F.Fab")
		)
		(fp_line
			(start -0.12065 -0.305054)
			(end -0.12065 -0.2794)
			(stroke
				(width 0.1)
				(type default)
			)
			(layer "F.Fab")
		)
		(pad "1" smd circle
			(at -0.40005 0 270)
			(size 0 0)
			(layers "F.Cu" "F.Mask" "F.Paste")
			(net "GND")
		)
		(pad "2" smd circle
			(at 0.40005 0 270)
			(size 0 0)
			(layers "F.Cu" "F.Mask" "F.Paste")
			(net "P12V_E1S_REG_0")
		)
	)
	(footprint ""
		(layer "F.Cu")
		(at 348.390464 -356.478332 180)
		(property "Reference" "R2590"
			(at 0 0 180)
			(layer "F.SilkS")
			(hide yes)
			(effects
				(font
					(size 1.27 1.27)
				)
			)
		)
		(property "Value" ""
			(at 0 0 180)
			(layer "F.Fab")
			(effects
				(font
					(size 1.27 1.27)
				)
			)
		)
		(duplicate_pad_numbers_are_jumpers no)
		(fp_line
			(start 0.7874 0.4064)
			(end -0.7874 0.4064)
			(stroke
				(width 0.1524)
				(type default)
			)
			(layer "F.SilkS")
		)
		(fp_line
			(start 0.7874 -0.4064)
			(end 0.7874 0.4064)
			(stroke
				(width 0.1524)
				(type default)
			)
			(layer "F.SilkS")
		)
		(fp_line
			(start -0.7874 0.4064)
			(end -0.7874 -0.4064)
			(stroke
				(width 0.1524)
				(type default)
			)
			(layer "F.SilkS")
		)
		(fp_line
			(start -0.7874 -0.4064)
			(end 0.7874 -0.4064)
			(stroke
				(width 0.1524)
				(type default)
			)
			(layer "F.SilkS")
		)
		(fp_line
			(start 0.67945 0.3048)
			(end 0.120396 0.3048)
			(stroke
				(width 0.1)
				(type default)
			)
			(layer "F.Fab")
		)
		(fp_line
			(start 0.67945 -0.3048)
			(end 0.67945 0.3048)
			(stroke
				(width 0.1)
				(type default)
			)
			(layer "F.Fab")
		)
		(fp_line
			(start 0.12065 -0.2794)
			(end 0.12065 -0.3048)
			(stroke
				(width 0.1)
				(type default)
			)
			(layer "F.Fab")
		)
		(fp_line
			(start 0.12065 -0.3048)
			(end 0.67945 -0.3048)
			(stroke
				(width 0.1)
				(type default)
			)
			(layer "F.Fab")
		)
		(fp_line
			(start 0.120396 0.3048)
			(end 0.120396 0.2794)
			(stroke
				(width 0.1)
				(type default)
			)
			(layer "F.Fab")
		)
		(fp_line
			(start 0.120396 0.2794)
			(end -0.12065 0.2794)
			(stroke
				(width 0.1)
				(type default)
			)
			(layer "F.Fab")
		)
		(fp_line
			(start -0.12065 0.3048)
			(end -0.67945 0.3048)
			(stroke
				(width 0.1)
				(type default)
			)
			(layer "F.Fab")
		)
		(fp_line
			(start -0.12065 0.2794)
			(end -0.12065 0.3048)
			(stroke
				(width 0.1)
				(type default)
			)
			(layer "F.Fab")
		)
		(fp_line
			(start -0.12065 -0.2794)
			(end 0.12065 -0.2794)
			(stroke
				(width 0.1)
				(type default)
			)
			(layer "F.Fab")
		)
		(fp_line
			(start -0.12065 -0.305054)
			(end -0.12065 -0.2794)
			(stroke
				(width 0.1)
				(type default)
			)
			(layer "F.Fab")
		)
		(fp_line
			(start -0.67945 0.3048)
			(end -0.67945 -0.305054)
			(stroke
				(width 0.1)
				(type default)
			)
			(layer "F.Fab")
		)
		(fp_line
			(start -0.67945 -0.305054)
			(end -0.12065 -0.305054)
			(stroke
				(width 0.1)
				(type default)
			)
			(layer "F.Fab")
		)
		(pad "1" smd circle
			(at -0.40005 0 180)
			(size 0 0)
			(layers "F.Cu" "F.Mask" "F.Paste")
			(net "SVID_DIO0_CPU0_R")
		)
		(pad "2" smd circle
			(at 0.40005 0 180)
			(size 0 0)
			(layers "F.Cu" "F.Mask" "F.Paste")
			(net "PVNN_TERM_CPU0")
		)
	)
)
